(kicad_pcb
	(version 20260206)
	(generator "pcbnew")
	(generator_version "10.0")
	(general
		(thickness 1.21888)
		(legacy_teardrops no)
	)
	(paper "A4")
	(title_block
		(title "timecard-beta-v1 — TimeCard-DC-V1.PcbDoc")
		(comment 1 "Time Appliance Project (Time Card) / footprint 22 of 120 (P1), pads 269-340 of 340")
	)
	(layers
		(0 "F.Cu" signal "TOP")
		(4 "In1.Cu" signal "SGND")
		(6 "In2.Cu" signal "IN1")
		(8 "In3.Cu" signal "IN2")
		(10 "In4.Cu" signal "SGND1")
		(2 "B.Cu" signal "BOTTOM")
		(9 "F.Adhes" user "F.Adhesive")
		(11 "B.Adhes" user "B.Adhesive")
		(13 "F.Paste" user "Top Paste")
		(15 "B.Paste" user "Bottom Paste")
		(5 "F.SilkS" user "Top Overlay")
		(7 "B.SilkS" user "Bottom Overlay")
		(1 "F.Mask" user "Top Solder")
		(3 "B.Mask" user "Bottom Solder")
		(17 "Dwgs.User" user "User.Drawings")
		(19 "Cmts.User" user "User.Comments")
		(21 "Eco1.User" user "User.Eco1")
		(23 "Eco2.User" user "User.Eco2")
		(25 "Edge.Cuts" user)
		(27 "Margin" user)
		(31 "F.CrtYd" user "Top Courtyard")
		(29 "B.CrtYd" user "Bottom Courtyard")
		(35 "F.Fab" user "Top Component Center")
		(33 "B.Fab" user "Bottom Component Center")
	)
	(footprint "FPGA_CONN:FPGA_CONN"
		(locked yes)
		(layer "F.Cu")
		(at 125.389655 117.4386)
		(property "Reference" "P1"
			(at -27.35726 -23.265455 0)
			(unlocked yes)
			(layer "F.SilkS")
			(effects
				(font
					(size 0.762 0.762)
					(thickness 0.2286)
				)
				(justify left bottom)
			)
		)
		(property "Value" "FPGA_CONN"
			(at -43.9575 52.70297 0)
			(unlocked yes)
			(layer "F.SilkS")
			(hide yes)
			(effects
				(font
					(size 1.524 1.524)
					(thickness 0.254)
				)
				(justify left bottom)
			)
		)
		(sheetname "FPGA")
		(sheetfile "FPGA.kicad_sch")
		(duplicate_pad_numbers_are_jumpers no)
		(pad "D-17" smd rect
			(at 4.79895 16.77035)
			(size 0.24994 1.54991)
			(layers "F.Cu" "F.Mask" "F.Paste")
			(net "PCIE_TX3_P")
		)
		(pad "D-18" smd rect
			(at 4.79895 20.82013)
			(size 0.24994 1.54991)
			(layers "F.Cu" "F.Mask" "F.Paste")
			(net "PCIE_RX2_P")
		)
		(pad "D-19" smd rect
			(at 4.29882 16.77035)
			(size 0.24994 1.54991)
			(layers "F.Cu" "F.Mask" "F.Paste")
			(net "PCIE_TX3_N")
		)
		(pad "D-20" smd rect
			(at 4.29882 20.82013)
			(size 0.24994 1.54991)
			(layers "F.Cu" "F.Mask" "F.Paste")
			(net "PCIE_RX2_N")
		)
		(pad "D-21" smd rect
			(at 3.79895 16.77035)
			(size 0.24994 1.54991)
			(layers "F.Cu" "F.Mask" "F.Paste")
			(net "GND")
		)
		(pad "D-22" smd rect
			(at 3.79895 20.82013)
			(size 0.24994 1.54991)
			(layers "F.Cu" "F.Mask" "F.Paste")
		)
		(pad "D-23" smd rect
			(at 3.29882 16.77035)
			(size 0.24994 1.54991)
			(layers "F.Cu" "F.Mask" "F.Paste")
			(net "PCIE_RX3_P")
		)
		(pad "D-24" smd rect
			(at 3.29882 20.82013)
			(size 0.24994 1.54991)
			(layers "F.Cu" "F.Mask" "F.Paste")
			(net "PCIE_TX1_P")
		)
		(pad "D-25" smd rect
			(at 2.79895 16.77035)
			(size 0.24994 1.54991)
			(layers "F.Cu" "F.Mask" "F.Paste")
			(net "PCIE_RX3_N")
		)
		(pad "D-26" smd rect
			(at 2.79895 20.82013)
			(size 0.24994 1.54991)
			(layers "F.Cu" "F.Mask" "F.Paste")
			(net "PCIE_TX1_N")
		)
		(pad "D-27" smd rect
			(at 2.29883 16.77035)
			(size 0.24994 1.54991)
			(layers "F.Cu" "F.Mask" "F.Paste")
			(net "GND")
		)
		(pad "D-28" smd rect
			(at 2.29883 20.82013)
			(size 0.24994 1.54991)
			(layers "F.Cu" "F.Mask" "F.Paste")
		)
		(pad "D-29" smd rect
			(at 1.79895 16.77035)
			(size 0.24994 1.54991)
			(layers "F.Cu" "F.Mask" "F.Paste")
			(net "PCIE_TX0_P")
		)
		(pad "D-30" smd rect
			(at 1.79895 20.82013)
			(size 0.24994 1.54991)
			(layers "F.Cu" "F.Mask" "F.Paste")
			(net "PCIE_RX1_P")
		)
		(pad "D-31" smd rect
			(at 1.29883 16.77035)
			(size 0.24994 1.54991)
			(layers "F.Cu" "F.Mask" "F.Paste")
			(net "PCIE_TX0_N")
		)
		(pad "D-32" smd rect
			(at 1.29883 20.82013)
			(size 0.24994 1.54991)
			(layers "F.Cu" "F.Mask" "F.Paste")
			(net "PCIE_RX1_N")
		)
		(pad "D-33" smd rect
			(at 0.79896 16.77035)
			(size 0.24994 1.54991)
			(layers "F.Cu" "F.Mask" "F.Paste")
			(net "GND")
		)
		(pad "D-34" smd rect
			(at 0.79896 20.82013)
			(size 0.24994 1.54991)
			(layers "F.Cu" "F.Mask" "F.Paste")
		)
		(pad "D-35" smd rect
			(at 0.29883 16.77035)
			(size 0.24994 1.54991)
			(layers "F.Cu" "F.Mask" "F.Paste")
			(net "PCIE_RX0_P")
		)
		(pad "D-36" smd rect
			(at 0.29883 20.82013)
			(size 0.24994 1.54991)
			(layers "F.Cu" "F.Mask" "F.Paste")
			(net "PCIE_CLK_P")
		)
		(pad "D-37" smd rect
			(at -0.20104 16.77035)
			(size 0.24994 1.54991)
			(layers "F.Cu" "F.Mask" "F.Paste")
			(net "PCIE_RX0_N")
		)
		(pad "D-38" smd rect
			(at -0.20104 20.82013)
			(size 0.24994 1.54991)
			(layers "F.Cu" "F.Mask" "F.Paste")
			(net "PCIE_CLK_N")
		)
		(pad "D-39" smd rect
			(at -0.70117 16.77035)
			(size 0.24994 1.54991)
			(layers "F.Cu" "F.Mask" "F.Paste")
			(net "GND")
		)
		(pad "D-40" smd rect
			(at -0.70117 20.82013)
			(size 0.24994 1.54991)
			(layers "F.Cu" "F.Mask" "F.Paste")
			(net "GND")
		)
		(pad "D-41" smd rect
			(at -1.20104 16.77035)
			(size 0.24994 1.54991)
			(layers "F.Cu" "F.Mask" "F.Paste")
		)
		(pad "D-42" smd rect
			(at -1.20104 20.82013)
			(size 0.24994 1.54991)
			(layers "F.Cu" "F.Mask" "F.Paste")
		)
		(pad "D-43" smd rect
			(at -1.70117 16.77035)
			(size 0.24994 1.54991)
			(layers "F.Cu" "F.Mask" "F.Paste")
		)
		(pad "D-44" smd rect
			(at -1.70117 20.82013)
			(size 0.24994 1.54991)
			(layers "F.Cu" "F.Mask" "F.Paste")
		)
		(pad "D-45" smd rect
			(at -2.20104 16.77035)
			(size 0.24994 1.54991)
			(layers "F.Cu" "F.Mask" "F.Paste")
		)
		(pad "D-46" smd rect
			(at -2.20104 20.82013)
			(size 0.24994 1.54991)
			(layers "F.Cu" "F.Mask" "F.Paste")
		)
		(pad "D-47" smd rect
			(at -2.70116 16.77035)
			(size 0.24994 1.54991)
			(layers "F.Cu" "F.Mask" "F.Paste")
		)
		(pad "D-48" smd rect
			(at -2.70116 20.82013)
			(size 0.24994 1.54991)
			(layers "F.Cu" "F.Mask" "F.Paste")
		)
		(pad "D-49" smd rect
			(at -3.20104 16.77035)
			(size 0.24994 1.54991)
			(layers "F.Cu" "F.Mask" "F.Paste")
			(net "GND")
		)
		(pad "D-50" smd rect
			(at -3.20104 20.82013)
			(size 0.24994 1.54991)
			(layers "F.Cu" "F.Mask" "F.Paste")
			(net "GND")
		)
		(pad "D-51" smd rect
			(at -3.70116 16.77035)
			(size 0.24994 1.54991)
			(layers "F.Cu" "F.Mask" "F.Paste")
		)
		(pad "D-52" smd rect
			(at -3.70116 20.82013)
			(size 0.24994 1.54991)
			(layers "F.Cu" "F.Mask" "F.Paste")
		)
		(pad "D-53" smd rect
			(at -4.20103 16.77035)
			(size 0.24994 1.54991)
			(layers "F.Cu" "F.Mask" "F.Paste")
		)
		(pad "D-54" smd rect
			(at -4.20103 20.82013)
			(size 0.24994 1.54991)
			(layers "F.Cu" "F.Mask" "F.Paste")
		)
		(pad "D-55" smd rect
			(at -4.70116 16.77035)
			(size 0.24994 1.54991)
			(layers "F.Cu" "F.Mask" "F.Paste")
		)
		(pad "D-56" smd rect
			(at -4.70116 20.82013)
			(size 0.24994 1.54991)
			(layers "F.Cu" "F.Mask" "F.Paste")
		)
		(pad "D-57" smd rect
			(at -5.20103 16.77035)
			(size 0.24994 1.54991)
			(layers "F.Cu" "F.Mask" "F.Paste")
		)
		(pad "D-58" smd rect
			(at -5.20103 20.82013)
			(size 0.24994 1.54991)
			(layers "F.Cu" "F.Mask" "F.Paste")
		)
		(pad "D-59" smd rect
			(at -5.70116 16.77035)
			(size 0.24994 1.54991)
			(layers "F.Cu" "F.Mask" "F.Paste")
			(net "GND")
		)
		(pad "D-60" smd rect
			(at -5.70116 20.82013)
			(size 0.24994 1.54991)
			(layers "F.Cu" "F.Mask" "F.Paste")
			(net "GND")
		)
		(pad "D-61" smd rect
			(at -6.20103 16.77035)
			(size 0.24994 1.54991)
			(layers "F.Cu" "F.Mask" "F.Paste")
		)
		(pad "D-62" smd rect
			(at -6.20103 20.82013)
			(size 0.24994 1.54991)
			(layers "F.Cu" "F.Mask" "F.Paste")
		)
		(pad "D-63" smd rect
			(at -6.70116 16.77035)
			(size 0.24994 1.54991)
			(layers "F.Cu" "F.Mask" "F.Paste")
		)
		(pad "D-64" smd rect
			(at -6.70116 20.82013)
			(size 0.24994 1.54991)
			(layers "F.Cu" "F.Mask" "F.Paste")
		)
		(pad "D-65" smd rect
			(at -7.20103 16.77035)
			(size 0.24994 1.54991)
			(layers "F.Cu" "F.Mask" "F.Paste")
		)
		(pad "D-66" smd rect
			(at -7.20103 20.82013)
			(size 0.24994 1.54991)
			(layers "F.Cu" "F.Mask" "F.Paste")
		)
		(pad "D-67" smd rect
			(at -7.70115 16.77035)
			(size 0.24994 1.54991)
			(layers "F.Cu" "F.Mask" "F.Paste")
		)
		(pad "D-68" smd rect
			(at -7.70115 20.82013)
			(size 0.24994 1.54991)
			(layers "F.Cu" "F.Mask" "F.Paste")
		)
		(pad "D-69" smd rect
			(at -8.20103 16.77035)
			(size 0.24994 1.54991)
			(layers "F.Cu" "F.Mask" "F.Paste")
			(net "GND")
		)
		(pad "D-70" smd rect
			(at -8.20103 20.82013)
			(size 0.24994 1.54991)
			(layers "F.Cu" "F.Mask" "F.Paste")
			(net "GND")
		)
		(pad "D-71" smd rect
			(at -8.70115 16.77035)
			(size 0.24994 1.54991)
			(layers "F.Cu" "F.Mask" "F.Paste")
		)
		(pad "D-72" smd rect
			(at -8.70115 20.82013)
			(size 0.24994 1.54991)
			(layers "F.Cu" "F.Mask" "F.Paste")
		)
		(pad "D-73" smd rect
			(at -9.20102 16.77035)
			(size 0.24994 1.54991)
			(layers "F.Cu" "F.Mask" "F.Paste")
		)
		(pad "D-74" smd rect
			(at -9.20102 20.82013)
			(size 0.24994 1.54991)
			(layers "F.Cu" "F.Mask" "F.Paste")
		)
		(pad "D-75" smd rect
			(at -9.70115 16.77035)
			(size 0.24994 1.54991)
			(layers "F.Cu" "F.Mask" "F.Paste")
		)
		(pad "D-76" smd rect
			(at -9.70115 20.82013)
			(size 0.24994 1.54991)
			(layers "F.Cu" "F.Mask" "F.Paste")
		)
		(pad "D-77" smd rect
			(at -10.20102 16.77035)
			(size 0.24994 1.54991)
			(layers "F.Cu" "F.Mask" "F.Paste")
		)
		(pad "D-78" smd rect
			(at -10.20102 20.82013)
			(size 0.24994 1.54991)
			(layers "F.Cu" "F.Mask" "F.Paste")
		)
		(pad "D-79" smd rect
			(at -10.70115 16.77035)
			(size 0.24994 1.54991)
			(layers "F.Cu" "F.Mask" "F.Paste")
		)
		(pad "D-80" smd rect
			(at -10.70115 20.82013)
			(size 0.24994 1.54991)
			(layers "F.Cu" "F.Mask" "F.Paste")
		)
		(pad "D-81" smd rect
			(at 10.225 18.8)
			(size 1.35001 1.70002)
			(layers "F.Cu" "F.Mask" "F.Paste")
		)
		(pad "D-82" thru_hole circle
			(at 9.04888 18.79524)
			(size 0.55016 0.55016)
			(drill 0.55016)
			(layers "*.Cu" "*.Mask")
			(remove_unused_layers no)
			(thermal_bridge_angle 90)
		)
		(pad "D-83" thru_hole circle
			(at -10.95108 18.79524)
			(size 0.55016 0.55016)
			(drill 0.55016)
			(layers "*.Cu" "*.Mask")
			(remove_unused_layers no)
			(thermal_bridge_angle 90)
		)
		(pad "D-84" smd rect
			(at -12.125 18.8)
			(size 1.35001 1.70002)
			(layers "F.Cu" "F.Mask" "F.Paste")
		)
		(pad "MNT-1" thru_hole rect
			(at -24.95156 -20.00834)
			(size 0 0)
			(drill 2.99999)
			(layers "*.Cu" "*.Mask")
			(remove_unused_layers no)
		)
		(pad "MNT-2" thru_hole rect
			(at 24.98484 -20.00834)
			(size 0 0)
			(drill 2.99999)
			(layers "*.Cu" "*.Mask")
			(remove_unused_layers no)
		)
		(pad "MNT-3" thru_hole rect
			(at 24.98484 19.86966)
			(size 0 0)
			(drill 2.99999)
			(layers "*.Cu" "*.Mask")
			(remove_unused_layers no)
		)
		(pad "MNT-4" thru_hole rect
			(at -24.92616 19.86966)
			(size 0 0)
			(drill 2.99999)
			(layers "*.Cu" "*.Mask")
			(remove_unused_layers no)
		)
	)
)
